# S9S_MB_2U (Grand Teton) — schematic parts with pin connectivity, parts 5884–5884 of 6093; source: Cadence DE-HDL packaged netlist (pstxprt.dat, pstxnet.dat, pstchip.dat)

U4  EMMITSBURG_REV0P9  GFNOCPU04302300-QV2N-MM#99A1WT IC  pkg BGA749_22X23  page 179  (pins 303-604 of 749)
  AY3  VSS_AY3  POWER  = GND
  AY5  VSS_AY5  POWER  = GND
  AY8  VSS_AY8  POWER  = GND
  AY11  VSS_AY11  POWER  = GND
  AY15  VSS_AY15  POWER  = GND
  AY18  VSS_AY18  POWER  = GND
  AY21  VSS_AY21  POWER  = GND
  AY24  VSS_AY24  POWER  = GND
  AY28  VSS_AY28  POWER  = GND
  AY31  VSS_AY31  POWER  = GND
  AY34  VSS_AY34  POWER  = GND
  AY37  VSS_AY37  POWER  = GND
  AY39  VSS_AY39  POWER  = GND
  AY41  USB2P_10  BI  = TP_USB2_10_DP
  AY43  USB2N_10  BI  = TP_USB2_10_DN
  B5  CLKOUT_SRC_N_15  OUT  = TP_CLK_100M_PCH_15_DN
  B7  CLKOUT_SRC_N_14  OUT  = TP_CLK_100M_PCH_14_DN
  B9  VSS_B9  POWER  = GND
  B11  CLKOUT_SRC_N_6  OUT  = CLK_100M_BMC_P3E_DN
  B13  VSS_B13  POWER  = GND
  B15  CLKOUT_SRC_N_9  OUT  = TP_CLK_100M_PCH_9_DN
  B17  CLKOUT_SRC_N_3  OUT  = CLK_100M_E1S_0_R_DN
  B19  CLKOUT_SRC_N_4  OUT  = TP_CLK_100M_PCH_4_DN
  B21  REFCLK_INJ_S_P  IN  = CLK_100M_CK440_PCH_EXTCLK_DP
  B23  XTAL_IN  IN  = XTAL_PCH_25M_IN
  B25  REFCLK_INJ_NS_P  IN  = CLK_25M_PCH_REF_NS_DP
  B27  PMSYNC_CLK_P_0  OUT  = CLK_25M_PCH_CPU0_DP
  B29  VSS_B29  POWER  = GND
  B31  DMI_1_RXN  IN  = DMI_CPU0_PCH_TX_C_DN<1>
  B33  DMI_3_RXN  IN  = DMI_CPU0_PCH_TX_C_DN<3>
  B35  DMI_5_SATA_18_PCIE3_18_RXN  IN  = DMI_CPU0_PCH_TX_C_DN<5>
  B37  DMI_7_SATA_16_PCIE3_16_RXN  IN  = DMI_CPU0_PCH_TX_C_DN<7>
  B39  VSS_B39  POWER  = GND
  BA2  GPPC_C_15_ME_SML4CLK  BI  = PU_SMB_SML4_3V3AUX_PCH_SCL
  BA4  GPPC_C_1_ME_SML0DATA  BI  = SMB_SML0_3V3AUX_PCH_SDA
  BA7  GPPC_S_7_SUSACK_N  BI  = FM_SUSACK_N
  BA10  SPI0_FLASH_1_CS_N  OUT  = TP_SPI_PCH_CS1_R_N
  BA13  SPI0_MOSI_IO_0  BI  = SPI_PCH_IO0
  BA16  SPI0_IO_3  BI  = SPI_PCH_IO3
  BA20  GPP_E_18_ERR1_N  BI  = FM_PS_PWROK_DLY_R_SEL
  BA23  GPP_E_1_SATA1_XPCIE_1  BI  = TP_PCH_GPP_E_1
  BA26  GPP_E_0_SATA1_XPCIE_0  BI  = TP_PCH_GPP_E_0
  BA29  GPP_E_9_SATA0_SLOAD_SATA0_DEVSLP  BI  = PD_PCH_GPP_E_9
  BA32  GPP_E_13_SATA1_SDATAOUT_SATA1_DEVSLP  BI  = PD_PCH_GPP_E_13
  BA36  GPP_E_17_ERR0_N  BI  = FM_DEBUG_PORT_PRSNT_R_N
  BA40  USB2P_12  BI  = TP_USB2_12_DP
  BA42  USB2N_12  BI  = TP_USB2_12_DN
  BB1  VSS_BB1  POWER  = GND
  BB3  GPPC_C_4_ME_SML0BCLK  BI  = SMB_SML0B_3V3AUX_SCL
  BB5  VSS_BB5  POWER  = GND
  BB8  GPPC_S_11  BI  = FM_ESPI_CS_SWIZZLE
  BB11  SPI0_TPM_CS_N  OUT  = SPI_PCH_TPM_CS_N
  BB15  SPI0_CLK  OUT  = SPI_PCH_CLK
  BB18  GPPC_S_0_TIME_SYNC_0  BI  = FM_XTAL_INPUT_FREQUENCY_0_MGPIO
  BB21  GPP_E_3_SATA1_XPCIE_3  BI  = PD_PCH_GPP_E_3
  BB24  GPP_E_6_SATA0_USB3_XPCIE_0  BI  = FM_M2_E1S_E6_PEDET
  BB28  GPP_E_12_SATA1_SLOAD_SATA1_GP  BI  = PD_PCH_GPP_E_12
  BB31  GPP_E_19_ERR2_N  BI  = FM_TPM_PRSNT_N
  BB34  GPP_E_14_SATA2_SCLOCK_SATA2_LED_N  BI  = PD_PCH_GPP_E_14
  BB37  PRDY_N  BI  = H_DBP_PRDY_N_PCH
  BB39  VSS_BB39  POWER  = GND
  BB41  USB2_COMP  BI  = PD_PCH_USB2_COMP
  BB43  RSVD_BB43  TRI  = TP_PCH_RSVD<7>
  BC2  VSS_BC2  POWER  = GND
  BC4  GPPC_C_0_ME_SML0CLK  BI  = SMB_SML0_3V3AUX_PCH_SCL
  BC6  VSS_BC6  POWER  = GND
  BC8  VSS_BC8  POWER  = GND
  BC10  VSS_BC10  POWER  = GND
  BC12  VSS_BC12  POWER  = GND
  BC14  VSS_BC14  POWER  = GND
  BC16  VSS_BC16  POWER  = GND
  BC18  VSS_BC18  POWER  = GND
  BC20  VSS_BC20  POWER  = GND
  BC22  VSS_BC22  POWER  = GND
  BC24  VSS_BC24  POWER  = GND
  BC26  VSS_BC26  POWER  = GND
  BC28  VSS_BC28  POWER  = GND
  BC30  VSS_BC30  POWER  = GND
  BC32  VSS_BC32  POWER  = GND
  BC34  VSS_BC34  POWER  = GND
  BC36  VSS_BC36  POWER  = GND
  BC38  VSS_BC38  POWER  = GND
  BC40  RSVD_BC40  TRI  = NC_PCH_RSVD<14>
  BC42  VSS_BC42  POWER  = GND
  BD1  VSS_BD1  POWER  = GND
  BD3  VSS_BD3  POWER  = GND
  BD5  VSS_BD5  POWER  = GND
  BD7  RCTRST_N  IN  = RST_RTCRST_N
  BD9  RSMRST_N  IN  = RST_RSMRST_PCH_N
  BD11  GPPC_A_16_SRCCLKREQ_N_6  BI  = FM_PCH_SATA_RAID_KEY
  BD13  GPPC_A_9_ESPI_CLK  BI  = CLK_24M_66M_LPC0_ESPI
  BD15  GPPC_A_1_ESPI_ALERT1_N  BI  = ESPI_ALERT1_N_LPC_RCIN_N
  BD17  GPPC_A_10_SRCCLKREQ_N_0  BI  = PD_PCH_GPPC_A_10
  BD19  GPPC_A_5_ESPI_IO_3  BI  = ESPI_LAD0_DATA_IO3
  BD21  VSS_BD21  POWER  = GND
  BD23  GPPC_B_23  BI  = JTAG_TRC_PCH_PTI1_CLK
  BD25  GPPC_B_18_HS_UART1_RTS_N  BI  = JTAG_TRC_PCH_PTI<11>
  BD27  GPPC_B_15_HS_UART0_CTS_N  BI  = JTAG_TRC_PCH_PTI<8>
  BD29  GPPC_B_12_HS_UART0_RXD  BI  = JTAG_TRC_PCH_PTI<5>
  BD31  GPPC_B_3_GSXRESET_N  BI  = JTAG_TRC_PCH_PTI<2>
  BD33  GPPC_B_0_GSXDOUT  BI  = JTAG_TRC_PCH_PTI0_CLK
  BD35  JTAGX  BI  = JTAG_DBP_CPU_GTL_TCK
  BD37  JTAG_TMS  BI  = JTAG_DBP_TMS_PCH
  BD39  VSS_BD39  POWER  = GND
  BD41  VSS_BD41  POWER  = GND
  BD43  VSS_BD43  POWER  = GND
  BE1  VSS_BE1  POWER  = GND
  BE3  VSS_BE3  POWER  = GND
  BE4  PCH_PWROK  IN  = PWRGD_PCH_PWROK
  BE6  RTCX1  IN  = XTAL_PCH_RTC1
  BE8  DSW_PWROK  IN  = PWRGD_DSW_PWROK
  BE10  VSS_BE10  POWER  = GND
  BE12  GPPC_A_14_SRCCLKREQ_N_4  BI  = PD_PCH_GPPC_A_14
  BE14  GPPC_A_15_SRCCLKREQ_N_5  BI  = PD_PCH_GPPC_A_15
  BE16  GPPC_A_7_ESPI_CS1_N  BI  = IRQ_LPC_SERIRQ_ESPI_CS1_N
  BE18  GPPC_A_4_ESPI_IO_2  BI  = ESPI_LAD0_DATA_IO2
  BE20  GPPC_A_6_ESPI_CS0_N  BI  = ESPI_LFRAME_N_BMC_CS0_N
  BE22  GPPC_B_22  BI  = JTAG_TRC_PCH_PTI<15>
  BE24  GPPC_B_20  BI  = JTAG_TRC_PCH_PTI<13>
  BE26  GPPC_B_16_HS_UART1_RXD  BI  = JTAG_TRC_PCH_PTI<9>
  BE28  GPPC_B_13_HS_UART0_TXD  BI  = JTAG_TRC_PCH_PTI<6>
  BE30  GPPC_B_4_GSXCLK  BI  = JTAG_TRC_PCH_PTI<3>
  BE32  GPPC_B_1_GSXSLOAD  BI  = JTAG_TRC_PCH_PTI<0>
  BE34  VSS_BE34  POWER  = GND
  BE36  JTAG_TDO  OUT  = JTAG_DBP_TDO_PCH
  BE38  JTAG_TDI  BI  = JTAG_DBP_TDI_PCH
  BE40  DBG_PMODE  OUT  = JTAG_DBP_PMODE
  BE41  VSS_BE41  POWER  = GND
  BE43  VSS_BE43  POWER  = GND
  BF5  RTC_EXTCAP  BI  = RTC_EXT_CAP
  BF7  RTCX2  OUT  = XTAL_PCH_RTC2
  BF9  SRTCRST_N  IN  = RST_SRTCRST_N
  BF11  GPPC_A_18_SRCCLKREQ_N_8  BI  = PD_PCH_GPPC_A_18
  BF13  GPPC_A_17_SRCCLKREQ_N_7  BI  = IRQ_BMC_PCH_NMI
  BF15  GPPC_A_13_SRCCLKREQ_N_3  BI  = FM_BMC_READY_R_N
  BF17  GPPC_A_8_ESPI_RESET_N  BI  = RST_ESPI_RESET_N
  BF19  GPPC_A_3_ESPI_IO_1  BI  = ESPI_LAD0_DATA_IO1
  BF21  VSS_BF21  POWER  = GND
  BF23  GPPC_B_21  BI  = JTAG_TRC_PCH_PTI<14>
  BF25  GPPC_B_19_HS_UART1_CTS_N  BI  = JTAG_TRC_PCH_PTI<12>
  BF27  GPPC_B_17_HS_UART1_TXD  BI  = JTAG_TRC_PCH_PTI<10>
  BF29  GPPC_B_14_HS_UART0_RTS_N  BI  = JTAG_TRC_PCH_PTI<7>
  BF31  GPPC_B_5_USB2_OCB_0  BI  = JTAG_TRC_PCH_PTI<4>
  BF33  GPPC_B_2_GSXDIN  BI  = JTAG_TRC_PCH_PTI<1>
  BF35  JTAG_TCK  BI  = JTAG_DBP_TCK_PCH
  BF37  PREQ_N  BI  = H_DBP_PREQ_N_PCH
  BF39  RSVD_BF39  TRI  = NC_PCH_RSVD<5>
  BG3  NC_CGC_DUT_DETECT_N  TRI  = TP_PCH_CGC_DUT_DETECTED
  BG4  VSS_BG4  POWER  = GND
  BG6  VSS_BG6  POWER  = GND
  BG8  INTRUDER_N  IN  = FM_INTRUDER_HDR_PCH_N
  BG10  VSS_BG10  POWER  = GND
  BG12  GPPC_A_2_ESPI_IO_0  BI  = ESPI_LAD0_DATA_IO0
  BG14  GPPC_A_19_SRCCLKREQ_N_9  BI  = PD_PCH_GPPC_A_19
  BG16  GPPC_A_12_SRCCLKREQ_N_2  BI  = M2_SSD0_CLKREQ_EN_N
  BG18  GPPC_A_11_SRCCLKREQ_N_1  BI  = E1S_0_CLKREQ_N
  BG20  GPPC_A_0_ESPI_ALERT0_N  BI  = IRQ_LPC_PIRQA_N_ESPI_ALERT0_N
  BG22  GPPC_B_11_USB2_OCB_6  BI  = PU_OC6_USB_N
  BG24  GPPC_B_10_USB2_OCB_5  BI  = PU_OC5_USB_N
  BG26  GPPC_B_9_USB2_OCB_4  BI  = PU_OC4_USB_N
  BG28  GPPC_B_8_USB2_OCB_3  BI  = PU_OC3_USB_N
  BG30  GPPC_B_7_USB2_OCB_2  BI  = PU_OC2_USB_N
  BG32  GPPC_B_6_USB2_OCB_1  BI  = USB_OC1_REAR_R_N
  BG34  VSS_BG34  POWER  = GND
  BG36  RSVD_BG36  TRI  = NC_PCH_RSVD<17>
  BG38  VSS_BG38  POWER  = GND
  BG40  VSS_BG40  POWER  = GND
  BG41  VSS_BG41  POWER  = GND
  C3  VSS_C3  POWER  = GND
  C4  VSS_C4  POWER  = GND
  C6  CLKOUT_SRC_P_15  OUT  = TP_CLK_100M_PCH_15_DP
  C8  CLKOUT_SRC_P_13  OUT  = TP_CLK_100M_PCH_13_DP
  C10  CLKOUT_SRC_P_12  OUT  = TP_CLK_100M_PCH_12_DP
  C12  CLKOUT_SRC_P_5  OUT  = TP_CLK_100M_PCH_5_DP
  C14  CLKOUT_SRC_P_7  OUT  = TP_CLK_100M_PCH_7_DP
  C16  CLKOUT_SRC_P_0  OUT  = TP_CLK_100M_PCH_0_DP
  C18  CLKOUT_SRC_P_16  OUT  = TP_CLK_100M_PCH_16_DP
  C20  VSS_C20  POWER  = GND
  C22  VSS_C22  POWER  = GND
  C24  VSS_C24  POWER  = GND
  C26  VSS_C26  POWER  = GND
  C28  PMSYNC_CLK_N_1  OUT  = CLK_25M_PCH_CPU1_DN
  C30  DMI_0_RXP  IN  = DMI_CPU0_PCH_TX_C_DP<0>
  C32  DMI_2_RXP  IN  = DMI_CPU0_PCH_TX_C_DP<2>
  C34  DMI_4_SATA_19_PCIE3_19_RXP  IN  = DMI_CPU0_PCH_TX_C_DP<4>
  C36  DMI_6_SATA_17_PCIE3_17_RXP  IN  = DMI_CPU0_PCH_TX_C_DP<6>
  C38  VSS_C38  POWER  = GND
  C40  RSVD_C40  TRI  = NC_PCH_RSVD<8>
  C41  VSS_C41  POWER  = GND
  C43  VSS_C43  POWER  = GND
  D1  VSS_D1  POWER  = GND
  D3  VSS_D3  POWER  = GND
  D5  VSS_D5  POWER  = GND
  D7  CLKOUT_SRC_P_14  OUT  = TP_CLK_100M_PCH_14_DP
  D9  VSS_D9  POWER  = GND
  D11  CLKOUT_SRC_P_6  OUT  = CLK_100M_BMC_P3E_DP
  D13  VSS_D13  POWER  = GND
  D15  CLKOUT_SRC_P_9  OUT  = TP_CLK_100M_PCH_9_DP
  D17  CLKOUT_SRC_P_3  OUT  = CLK_100M_E1S_0_R_DP
  D19  CLKOUT_SRC_P_4  OUT  = TP_CLK_100M_PCH_4_DP
  D21  REFCLK_INJ_S_N  IN  = CLK_100M_CK440_PCH_EXTCLK_DN
  D23  XTAL_OUT  OUT  = XTAL_PCH_25M_OUT
  D25  REFCLK_INJ_NS_N  IN  = CLK_25M_PCH_REF_NS_DN
  D27  PMSYNC_CLK_N_0  OUT  = CLK_25M_PCH_CPU0_DN
  D29  VSS_D29  POWER  = GND
  D31  DMI_1_RXP  IN  = DMI_CPU0_PCH_TX_C_DP<1>
  D33  DMI_3_RXP  IN  = DMI_CPU0_PCH_TX_C_DP<3>
  D35  DMI_5_SATA_18_PCIE3_18_RXP  IN  = DMI_CPU0_PCH_TX_C_DP<5>
  D37  DMI_7_SATA_16_PCIE3_16_RXP  IN  = DMI_CPU0_PCH_TX_C_DP<7>
  D39  RSVD_D39  TRI  = NC_PCH_RSVD<9>
  D41  VSS_D41  POWER  = GND
  D43  VSS_D43  POWER  = GND
  E2  VSS_E2  POWER  = GND
  E4  CPU_MEMTRIP_N  IN  = TP_PCH_CPU_MEMTRIP_N
  E6  VSS_E6  POWER  = GND
  E8  VSS_E8  POWER  = GND
  E10  VSS_E10  POWER  = GND
  E12  VSS_E12  POWER  = GND
  E14  VSS_E14  POWER  = GND
  E16  VSS_E16  POWER  = GND
  E18  VSS_E18  POWER  = GND
  E20  VSS_E20  POWER  = GND
  E22  VSS_E22  POWER  = GND
  E24  VSS_E24  POWER  = GND
  E26  VSS_E26  POWER  = GND
  E28  VSS_E28  POWER  = GND
  E30  VSS_E30  POWER  = GND
  E32  VSS_E32  POWER  = GND
  E34  VSS_E34  POWER  = GND
  E36  VSS_E36  POWER  = GND
  E38  VSS_E38  POWER  = GND
  E40  VSS_E40  POWER  = GND
  E42  VSS_E42  POWER  = GND
  F1  RSVD_F1  TRI  = TP_PCH_RSVD<1>
  F3  CPU_THRMTRIP_N  IN  = H_THERMTRIP_LVC1_N
  F5  CPU_PWR_DEBUG_N  OUT  = FM_PCH_CPU_PWR_DEBUG_N
  F8  CPU_CATERR_N  IN  = FM_PCIE_EV_BIF_EN
  F11  CPU_MSMI_N  IN  = TP_PCH_CPU_MSMI_N
  F15  VSS_F15  POWER  = GND
  F18  CLKOUT_SRC_N_8  OUT  = TP_CLK_100M_PCH_8_DN
  F21  CLKOUT_SRC_P_1  OUT  = TP_CLK_100M_PCH_1_DP
  F24  VSS_F24  POWER  = GND
  F28  DMI_1_TXP  OUT  = DMI_CPU0_PCH_RX_DP<1>
  F31  VSS_F31  POWER  = GND
  F34  VSS_F34  POWER  = GND
  F37  DMI_7_SATA_16_PCIE3_16_TXN  OUT  = DMI_CPU0_PCH_RX_DN<7>
  F39  VSS_F39  POWER  = GND
  F41  VSS_F41  POWER  = GND
  F43  VSS_F43  POWER  = GND
  G2  GPPC_H_16_FLEX_CLK_OUT_1  BI  = FM_PCH_RING_OSC_BYPASS_MGPIO_TE
  G4  GPPC_H_0  BI  = FM_PCH_VISA_DEFAULT
  G7  CPU_ERR1_N  IN  = H_CPU_ERR1_PCH_R_N
  G10  CPUPWRGD  OUT  = PWRGD_CPUPWRGD_GTL
  G13  VSS_G13  POWER  = GND
  G16  CLKOUT_SRC_N_11  OUT  = TP_CLK_100M_PCH_11_DN
  G20  VSS_G20  POWER  = GND
  G23  CLKOUT_SRC_N_1  OUT  = TP_CLK_100M_PCH_1_DN
  G26  VSS_G26  POWER  = GND
  G29  DMI_1_TXN  OUT  = DMI_CPU0_PCH_RX_DN<1>
  G32  DMI_4_SATA_19_PCIE3_19_TXP  OUT  = DMI_CPU0_PCH_RX_DP<4>
  G36  DMI_5_SATA_18_PCIE3_18_TXN  OUT  = DMI_CPU0_PCH_RX_DN<5>
  G40  SATA_15_PCIE3_15_RXN  IN  = TP_P3E_PCH_15_RX_DN
  G42  SATA_15_PCIE3_15_RXP  IN  = TP_P3E_PCH_15_RX_DP
  H1  RSVD_H1  TRI  = TP_PCH_RSVD<0>
  H3  GPPC_H_17_FLEX_CLK_OUT_2  BI  = FM_PCH_XTAL_INPUT_MODE_MGPIO_TE
  H5  VSS_H5  POWER  = GND
  H8  VSS_H8  POWER  = GND
  H11  TRIGGER0_N  BI  = FM_PCH_TRIGGER0_R_N
  H15  CLKOUT_SRC_P_11  OUT  = TP_CLK_100M_PCH_11_DP
  H18  CLKOUT_SRC_P_8  OUT  = TP_CLK_100M_PCH_8_DP
  H21  CLKOUT_SRC_N_2  OUT  = CLK_100M_PE_M2_0_R_DN
  H24  RSVD_H24  TRI  = TP_PCH_RSVD<18>
  H28  DMI_0_TXP  OUT  = DMI_CPU0_PCH_RX_DP<0>
  H31  DMI_2_TXP  OUT  = DMI_CPU0_PCH_RX_DP<2>
  H34  DMI_5_SATA_18_PCIE3_18_TXP  OUT  = DMI_CPU0_PCH_RX_DP<5>
  H37  DMI_7_SATA_16_PCIE3_16_TXP  OUT  = DMI_CPU0_PCH_RX_DP<7>
  H39  VSS_H39  POWER  = GND
  H41  SATA_14_PCIE3_14_GBE_2_RXN  IN  = TP_P3E_PCH_14_RX_DN
  H43  SATA_14_PCIE3_14_GBE_2_RXP  IN  = TP_P3E_PCH_14_RX_DP
  J2  GPPC_H_15_FLEX_CLK_OUT_0  BI  = TP_PCH_MGPIO_TEST1
  J4  GPPC_H_18_PMCALERT_N  BI  = PU_PCH_PMCALERT_N
  J7  CPU_ERR0_N  IN  = H_CPU_ERR0_PCH_R_N
  J10  ME_PECI  BI  = PECI_PCH
  J13  VSS_J13  POWER  = GND
  J16  CLKOUT_SRC_N_10  OUT  = TP_CLK_100M_PCH_10_DN
  J20  VSS_J20  POWER  = GND
  J23  RSVD_J23  TRI  = TP_PCH_RSVD<19>
  J26  VSS_J26  POWER  = GND
  J29  DMI_2_TXN  OUT  = DMI_CPU0_PCH_RX_DN<2>
  J32  DMI_4_SATA_19_PCIE3_19_TXN  OUT  = DMI_CPU0_PCH_RX_DN<4>
  J36  DMI_6_SATA_17_PCIE3_17_TXP  OUT  = DMI_CPU0_PCH_RX_DP<6>
  J40  SATA_13_PCIE3_13_RXN  IN  = TP_P3E_PCH_13_RX_DN
  J42  SATA_13_PCIE3_13_RXP  IN  = TP_P3E_PCH_13_RX_DP
  K1  GPPC_H_1  BI  = FM_PCH_IO_EXPANDER
  K3  GPPC_H_7  BI  = FM_PCH_MCRO_LDO
  K5  VSS_K5  POWER  = GND
  K8  TRIGGER1_N  BI  = FM_PCH_TRIGGER1_R_N
  K11  VSS_K11  POWER  = GND
  K15  VSS_K15  POWER  = GND
  K18  CLKOUT_SRC_P_10  OUT  = TP_CLK_100M_PCH_10_DP
  K21  CLKOUT_SRC_P_2  OUT  = CLK_100M_PE_M2_0_R_DP
  K24  VSS_K24  POWER  = GND
